# BASEBOARD_FAB2 (Tioga Pass) — schematic netlist excerpt (pin names and nets, part order shuffled) for the footprints in the layout excerpt that follows; sources: Cadence DE-HDL packaged netlist, KiCad conversion of Wiwynn_Tioga_Pass_MB.brd

R1W31  RES  330 5% CHIP  pkg 0402  page 89 : A = FM_ADR_COMPLETE_R ; B = FM_ADR_COMPLETE_CPU1_R
L4D3  IND-120NH-30-GP  pkg DISCRET-GB2  page 202 : S = VR_PVCCIN_CPU0_PHASE2 ; F = PVCCIN_CPU0
C3D11  CAP_A  22.0UF 4V 20% X6S  pkg 0603V  page 76 : A = PVCCMCP_CPU1 ; B = GND

(kicad_pcb
	(version 20260206)
	(generator "pcbnew")
	(generator_version "10.0")
	(general
		(thickness 1.6)
		(legacy_teardrops no)
	)
	(paper "A4")
	(title_block
		(title "Wiwynn_Tioga_Pass_MB.brd")
		(comment 1 "Tioga Pass / footprints 1634-1636 of 4770")
	)
	(layers
		(0 "F.Cu" signal "TOP")
		(4 "In1.Cu" signal "L2GND")
		(6 "In2.Cu" signal "L3")
		(8 "In3.Cu" signal "L4GND")
		(10 "In4.Cu" signal "L5")
		(12 "In5.Cu" signal "L6GND")
		(14 "In6.Cu" signal "L7VCC")
		(16 "In7.Cu" signal "L8VCC")
		(18 "In8.Cu" signal "L9GND")
		(20 "In9.Cu" signal "L10")
		(22 "In10.Cu" signal "L11GND")
		(24 "In11.Cu" signal "L12")
		(26 "In12.Cu" signal "L13GND")
		(2 "B.Cu" signal "BOTTOM")
		(9 "F.Adhes" user "F.Adhesive")
		(11 "B.Adhes" user "B.Adhesive")
		(13 "F.Paste" user "Package Geometry/Pastemask Top")
		(15 "B.Paste" user "Package Geometry/Pastemask Bottom")
		(5 "F.SilkS" user "Ref Des/Silkscreen Top")
		(7 "B.SilkS" user "Ref Des/Silkscreen Bottom")
		(1 "F.Mask" user "Board Geometry/Soldermask Top")
		(3 "B.Mask" user "Board Geometry/Soldermask Bottom")
		(17 "Dwgs.User" user "User.Drawings")
		(19 "Cmts.User" user "User.Comments")
		(21 "Eco1.User" user "User.Eco1")
		(23 "Eco2.User" user "User.Eco2")
		(25 "Edge.Cuts" user "Board Geometry/Outline")
		(27 "Margin" user)
		(31 "F.CrtYd" user "Package Geometry/Place Bound Top")
		(29 "B.CrtYd" user "Package Geometry/Place Bound Bottom")
		(35 "F.Fab" user "Ref Des/Assembly Top")
		(33 "B.Fab" user "Ref Des/Assembly Bottom")
	)
	(footprint ""
		(layer "F.Cu")
		(at 205.036928 -65.159382)
		(property "Reference" "L4D3"
			(at 3.378708 -4.251706 0)
			(unlocked yes)
			(layer "F.SilkS")
			(effects
				(font
					(size 0.4064 0.254)
					(thickness 0.1524)
				)
			)
		)
		(property "Value" ""
			(at 0 0 0)
			(layer "F.Fab")
			(effects
				(font
					(size 1.27 1.27)
				)
			)
		)
		(duplicate_pad_numbers_are_jumpers no)
		(fp_line
			(start -1.1303 -3.199892)
			(end 8.3693 -3.199892)
			(stroke
				(width 0.1524)
				(type default)
			)
			(layer "F.SilkS")
		)
		(fp_line
			(start -1.1303 -1.6637)
			(end -1.1303 -3.199892)
			(stroke
				(width 0.1524)
				(type default)
			)
			(layer "F.SilkS")
		)
		(fp_line
			(start -1.1303 3.199892)
			(end -1.1303 1.6637)
			(stroke
				(width 0.1524)
				(type default)
			)
			(layer "F.SilkS")
		)
		(fp_line
			(start 8.3693 -3.199892)
			(end 8.3693 -1.6637)
			(stroke
				(width 0.1524)
				(type default)
			)
			(layer "F.SilkS")
		)
		(fp_line
			(start 8.3693 1.6637)
			(end 8.3693 3.199892)
			(stroke
				(width 0.1524)
				(type default)
			)
			(layer "F.SilkS")
		)
		(fp_line
			(start 8.3693 3.199892)
			(end -1.1303 3.199892)
			(stroke
				(width 0.1524)
				(type default)
			)
			(layer "F.SilkS")
		)
		(fp_rect
			(start -1.1303 3.199892)
			(end 8.3693 -3.199892)
			(stroke
				(width 0)
				(type default)
			)
			(fill no)
			(layer "F.CrtYd")
		)
		(fp_line
			(start -1.1303 -3.199892)
			(end 8.3693 -3.199892)
			(stroke
				(width 0.1)
				(type default)
			)
			(layer "F.Fab")
		)
		(fp_line
			(start -1.1303 3.199892)
			(end -1.1303 -3.199892)
			(stroke
				(width 0.1)
				(type default)
			)
			(layer "F.Fab")
		)
		(fp_line
			(start 8.3693 -3.199892)
			(end 8.3693 3.199892)
			(stroke
				(width 0.1)
				(type default)
			)
			(layer "F.Fab")
		)
		(fp_line
			(start 8.3693 3.199892)
			(end -1.1303 3.199892)
			(stroke
				(width 0.1)
				(type default)
			)
			(layer "F.Fab")
		)
		(pad "1" smd rect
			(at 0 0)
			(size 3.683 2.667)
			(layers "F.Cu" "F.Mask" "F.Paste")
			(net "VR_PVCCIN_CPU0_PHASE2")
		)
		(pad "2" smd rect
			(at 7.239 0)
			(size 3.683 2.667)
			(layers "F.Cu" "F.Mask" "F.Paste")
			(net "PVCCIN_CPU0")
		)
	)
	(footprint ""
		(layer "F.Cu")
		(at 312.142124 -35.623754)
		(property "Reference" "R1W31"
			(at -0.8382 -0.67818 0)
			(unlocked yes)
			(layer "F.SilkS")
			(effects
				(font
					(size 0.4064 0.254)
					(thickness 0.1524)
				)
				(justify left)
			)
		)
		(property "Value" ""
			(at 0 0 0)
			(layer "F.Fab")
			(effects
				(font
					(size 1.27 1.27)
				)
			)
		)
		(duplicate_pad_numbers_are_jumpers no)
		(fp_poly
			(pts
				(xy -0.2794 -0.1016) (xy 0.2794 -0.1016) (xy 0.2794 0.9906) (xy -0.2794 0.9906)
			)
			(stroke
				(width 0)
				(type default)
			)
			(fill no)
			(layer "F.CrtYd")
		)
		(fp_line
			(start -0.2794 -0.1016)
			(end -0.2794 0.9906)
			(stroke
				(width 0.1)
				(type default)
			)
			(layer "F.Fab")
		)
		(fp_line
			(start -0.2794 0.9906)
			(end 0.2794 0.9906)
			(stroke
				(width 0.1)
				(type default)
			)
			(layer "F.Fab")
		)
		(fp_line
			(start 0.2794 -0.1016)
			(end -0.2794 -0.1016)
			(stroke
				(width 0.1)
				(type default)
			)
			(layer "F.Fab")
		)
		(fp_line
			(start 0.2794 0.9906)
			(end 0.2794 -0.1016)
			(stroke
				(width 0.1)
				(type default)
			)
			(layer "F.Fab")
		)
		(pad "1" smd rect
			(at 0 0)
			(size 0.508 0.508)
			(layers "F.Cu" "F.Mask" "F.Paste")
			(net "FM_ADR_COMPLETE_R")
		)
		(pad "2" smd rect
			(at 0 0.889)
			(size 0.508 0.508)
			(layers "F.Cu" "F.Mask" "F.Paste")
			(net "FM_ADR_COMPLETE_CPU1_R")
		)
		(zone
			(layer "F.Cu")
			(hatch none 0.5)
			(connect_pads
				(clearance 0)
			)
			(min_thickness 0.25)
			(keepout
				(tracks allowed)
				(vias not_allowed)
				(pads allowed)
				(copperpour not_allowed)
				(footprints allowed)
			)
			(placement
				(enabled no)
				(sheetname "")
			)
			(fill
				(thermal_gap 0.5)
				(thermal_bridge_width 0.5)
				(island_removal_mode 0)
			)
			(polygon
				(pts
					(xy 311.888124 -35.369754) (xy 312.396124 -35.369754) (xy 312.396124 -34.988754) (xy 311.888124 -34.988754)
				)
			)
		)
		(zone
			(layer "F.Cu")
			(hatch none 0.5)
			(connect_pads
				(clearance 0)
			)
			(min_thickness 0.25)
			(keepout
				(tracks not_allowed)
				(vias allowed)
				(pads allowed)
				(copperpour not_allowed)
				(footprints allowed)
			)
			(placement
				(enabled no)
				(sheetname "")
			)
			(fill
				(thermal_gap 0.5)
				(thermal_bridge_width 0.5)
				(island_removal_mode 0)
			)
			(polygon
				(pts
					(xy 311.888124 -34.988754) (xy 312.396124 -34.988754) (xy 312.396124 -35.369754) (xy 311.888124 -35.369754)
				)
			)
		)
	)
	(footprint ""
		(layer "F.Cu")
		(at 108.368592 -77.429614)
		(property "Reference" "C3D11"
			(at 0 0 0)
			(layer "F.SilkS")
			(hide yes)
			(effects
				(font
					(size 1.27 1.27)
				)
			)
		)
		(property "Value" ""
			(at 0 0 0)
			(layer "F.Fab")
			(effects
				(font
					(size 1.27 1.27)
				)
			)
		)
		(duplicate_pad_numbers_are_jumpers no)
		(fp_poly
			(pts
				(xy -0.4953 -0.2032) (xy 0.4953 -0.2032) (xy 0.4953 1.6002) (xy -0.4953 1.6002)
			)
			(stroke
				(width 0)
				(type default)
			)
			(fill no)
			(layer "F.CrtYd")
		)
		(fp_line
			(start -0.4953 -0.2032)
			(end 0.4953 -0.2032)
			(stroke
				(width 0.1)
				(type default)
			)
			(layer "F.Fab")
		)
		(fp_line
			(start -0.4953 1.6002)
			(end -0.4953 -0.2032)
			(stroke
				(width 0.1)
				(type default)
			)
			(layer "F.Fab")
		)
		(fp_line
			(start 0.4953 -0.2032)
			(end 0.4953 1.6002)
			(stroke
				(width 0.1)
				(type default)
			)
			(layer "F.Fab")
		)
		(fp_line
			(start 0.4953 1.6002)
			(end -0.4953 1.6002)
			(stroke
				(width 0.1)
				(type default)
			)
			(layer "F.Fab")
		)
		(pad "1" smd rect
			(at 0 0)
			(size 0.762 0.889)
			(layers "F.Cu" "F.Mask" "F.Paste")
			(net "PVCCMCP_CPU1")
		)
		(pad "2" smd rect
			(at 0 1.397)
			(size 0.762 0.889)
			(layers "F.Cu" "F.Mask" "F.Paste")
			(net "GND")
		)
		(zone
			(layer "F.Cu")
			(hatch none 0.5)
			(connect_pads
				(clearance 0)
			)
			(min_thickness 0.25)
			(keepout
				(tracks not_allowed)
				(vias allowed)
				(pads allowed)
				(copperpour not_allowed)
				(footprints allowed)
			)
			(placement
				(enabled no)
				(sheetname "")
			)
			(fill
				(thermal_gap 0.5)
				(thermal_bridge_width 0.5)
				(island_removal_mode 0)
			)
			(polygon
				(pts
					(xy 107.987592 -76.985114) (xy 108.749592 -76.985114) (xy 108.749592 -76.477114) (xy 107.987592 -76.477114)
				)
			)
		)
	)
)
